(kicad_pcb
	(version 20260206)
	(generator "pcbnew")
	(generator_version "10.0")
	(general
		(thickness 1.6)
		(legacy_teardrops no)
	)
	(paper "A4")
	(title_block
		(title "12092022_DA0F0TFB6D0_F0T_FAN_BOARD_MP5048_D_brd_v02_OCP.brd")
		(comment 1 "Grand Teton / footprints 812-818 of 924")
	)
	(layers
		(0 "F.Cu" signal "TOP")
		(4 "In1.Cu" signal "GND")
		(6 "In2.Cu" signal "IN1")
		(8 "In3.Cu" signal "IN2")
		(10 "In4.Cu" signal "GND1")
		(2 "B.Cu" signal "BOTTOM")
		(9 "F.Adhes" user "F.Adhesive")
		(11 "B.Adhes" user "B.Adhesive")
		(13 "F.Paste" user "Package Geometry/Pastemask Top")
		(15 "B.Paste" user "Package Geometry/Pastemask Bottom")
		(5 "F.SilkS" user "Ref Des/Silkscreen Top")
		(7 "B.SilkS" user "Ref Des/Silkscreen Bottom")
		(1 "F.Mask" user "Board Geometry/Soldermask Top")
		(3 "B.Mask" user "Board Geometry/Soldermask Bottom")
		(17 "Dwgs.User" user "User.Drawings")
		(19 "Cmts.User" user "User.Comments")
		(21 "Eco1.User" user "User.Eco1")
		(23 "Eco2.User" user "User.Eco2")
		(25 "Edge.Cuts" user "Board Geometry/Outline")
		(27 "Margin" user)
		(31 "F.CrtYd" user "Package Geometry/Place Bound Top")
		(29 "B.CrtYd" user "Package Geometry/Place Bound Bottom")
		(35 "F.Fab" user "Ref Des/Assembly Top")
		(33 "B.Fab" user "Ref Des/Assembly Bottom")
	)
	(footprint ""
		(layer "B.Cu")
		(at 46.471332 -63.532512 90)
		(property "Reference" "PD14"
			(at -5.518912 3.692398 270)
			(unlocked yes)
			(layer "B.SilkS")
			(effects
				(font
					(size 0.7874 0.5842)
					(thickness 0.1524)
				)
				(justify left mirror)
			)
		)
		(property "Value" ""
			(at 0 0 90)
			(layer "B.Fab")
			(effects
				(font
					(size 1.27 1.27)
				)
				(justify mirror)
			)
		)
		(duplicate_pad_numbers_are_jumpers no)
		(fp_line
			(start 4.647184 -3.109976)
			(end 4.647184 3.109976)
			(stroke
				(width 0.1524)
				(type default)
			)
			(layer "B.SilkS")
		)
		(fp_line
			(start -5.536184 -3.109976)
			(end 4.647184 -3.109976)
			(stroke
				(width 0.1524)
				(type default)
			)
			(layer "B.SilkS")
		)
		(fp_line
			(start -0.762 -1.143)
			(end -0.762 0.889)
			(stroke
				(width 0.1524)
				(type default)
			)
			(layer "B.SilkS")
		)
		(fp_line
			(start 0.635 -0.889)
			(end 0.635 0.635)
			(stroke
				(width 0.1524)
				(type default)
			)
			(layer "B.SilkS")
		)
		(fp_line
			(start 1.397 -0.127)
			(end 0.635 -0.127)
			(stroke
				(width 0.1524)
				(type default)
			)
			(layer "B.SilkS")
		)
		(fp_line
			(start -0.635 -0.127)
			(end 0.635 -0.889)
			(stroke
				(width 0.1524)
				(type default)
			)
			(layer "B.SilkS")
		)
		(fp_line
			(start -0.635 -0.127)
			(end -1.397 -0.127)
			(stroke
				(width 0.1524)
				(type default)
			)
			(layer "B.SilkS")
		)
		(fp_line
			(start 0.635 0.635)
			(end -0.635 -0.127)
			(stroke
				(width 0.1524)
				(type default)
			)
			(layer "B.SilkS")
		)
		(fp_line
			(start 4.647184 3.109976)
			(end -5.536184 3.109976)
			(stroke
				(width 0.1524)
				(type default)
			)
			(layer "B.SilkS")
		)
		(fp_line
			(start -5.536184 3.109976)
			(end -5.536184 -3.109976)
			(stroke
				(width 0.1524)
				(type default)
			)
			(layer "B.SilkS")
		)
		(fp_poly
			(pts
				(xy -5.5118 -3.0988) (xy -5.5118 3.1496) (xy -4.572 3.1496) (xy -4.572 -3.0988)
			)
			(stroke
				(width 0)
				(type default)
			)
			(fill yes)
			(layer "B.SilkS")
		)
		(fp_line
			(start 3.554984 -3.109976)
			(end 3.554984 3.109976)
			(stroke
				(width 0.1)
				(type default)
			)
			(layer "B.Fab")
		)
		(fp_line
			(start -3.554984 -3.109976)
			(end 3.554984 -3.109976)
			(stroke
				(width 0.1)
				(type default)
			)
			(layer "B.Fab")
		)
		(fp_line
			(start 3.554984 3.109976)
			(end -3.554984 3.109976)
			(stroke
				(width 0.1)
				(type default)
			)
			(layer "B.Fab")
		)
		(fp_line
			(start -3.554984 3.109976)
			(end -3.554984 -3.109976)
			(stroke
				(width 0.1)
				(type default)
			)
			(layer "B.Fab")
		)
		(fp_text user "+"
			(at 6.1214 -0.32385 90)
			(unlocked yes)
			(layer "B.SilkS")
			(effects
				(font
					(size 1.905 1.4224)
					(thickness 0.1524)
				)
				(justify left mirror)
			)
		)
		(fp_text user "-"
			(at -5.493512 0.931418 90)
			(unlocked yes)
			(layer "B.SilkS")
			(effects
				(font
					(size 1.905 1.4224)
					(thickness 0.1524)
				)
				(justify left mirror)
			)
		)
		(fp_text user "-"
			(at -5.334 -0.34925 90)
			(unlocked yes)
			(layer "B.Fab")
			(effects
				(font
					(size 1.905 1.4224)
					(thickness 0.1524)
				)
				(justify left mirror)
			)
		)
		(fp_text user "+"
			(at 6.1214 -0.32385 90)
			(unlocked yes)
			(layer "B.Fab")
			(effects
				(font
					(size 1.905 1.4224)
					(thickness 0.1524)
				)
				(justify left mirror)
			)
		)
		(pad "A" smd rect
			(at 3.299968 0 270)
			(size 2.413 3.302)
			(layers "B.Cu" "B.Mask" "B.Paste")
			(net "GND")
		)
		(pad "C" smd rect
			(at -3.299968 0 270)
			(size 2.413 3.302)
			(layers "B.Cu" "B.Mask" "B.Paste")
			(net "P52V_HSC")
		)
	)
	(footprint ""
		(layer "B.Cu")
		(at 6.09473 -48.413924)
		(property "Reference" "C2109"
			(at 0 0 0)
			(layer "B.SilkS")
			(hide yes)
			(effects
				(font
					(size 1.27 1.27)
				)
				(justify mirror)
			)
		)
		(property "Value" ""
			(at 0 0 0)
			(layer "B.Fab")
			(effects
				(font
					(size 1.27 1.27)
				)
				(justify mirror)
			)
		)
		(duplicate_pad_numbers_are_jumpers no)
		(fp_line
			(start -2.2098 -0.9398)
			(end -2.2098 0.9398)
			(stroke
				(width 0.1524)
				(type default)
			)
			(layer "B.SilkS")
		)
		(fp_line
			(start -2.2098 0.9398)
			(end 2.2098 0.9398)
			(stroke
				(width 0.1524)
				(type default)
			)
			(layer "B.SilkS")
		)
		(fp_line
			(start 2.2098 -0.9398)
			(end -2.2098 -0.9398)
			(stroke
				(width 0.1524)
				(type default)
			)
			(layer "B.SilkS")
		)
		(fp_line
			(start 2.2098 0.9398)
			(end 2.2098 -0.9398)
			(stroke
				(width 0.1524)
				(type default)
			)
			(layer "B.SilkS")
		)
		(fp_line
			(start -1.700022 -0.899922)
			(end -1.700022 0.899922)
			(stroke
				(width 0.1)
				(type default)
			)
			(layer "B.Fab")
		)
		(fp_line
			(start -1.700022 0.899922)
			(end 1.700022 0.899922)
			(stroke
				(width 0.1)
				(type default)
			)
			(layer "B.Fab")
		)
		(fp_line
			(start 1.700022 -0.899922)
			(end -1.700022 -0.899922)
			(stroke
				(width 0.1)
				(type default)
			)
			(layer "B.Fab")
		)
		(fp_line
			(start 1.700022 0.899922)
			(end 1.700022 -0.899922)
			(stroke
				(width 0.1)
				(type default)
			)
			(layer "B.Fab")
		)
		(pad "1" smd rect
			(at 1.4732 0)
			(size 1.1684 1.5748)
			(layers "B.Cu" "B.Mask" "B.Paste")
			(net "P52V_FAN_4")
		)
		(pad "2" smd rect
			(at -1.4732 0)
			(size 1.1684 1.5748)
			(layers "B.Cu" "B.Mask" "B.Paste")
			(net "GND")
		)
	)
	(footprint ""
		(layer "B.Cu")
		(at 16.782796 -272.097754 180)
		(property "Reference" "C2118"
			(at 0 0 0)
			(layer "B.SilkS")
			(hide yes)
			(effects
				(font
					(size 1.27 1.27)
				)
				(justify mirror)
			)
		)
		(property "Value" ""
			(at 0 0 0)
			(layer "B.Fab")
			(effects
				(font
					(size 1.27 1.27)
				)
				(justify mirror)
			)
		)
		(duplicate_pad_numbers_are_jumpers no)
		(fp_line
			(start 2.2098 0.9398)
			(end 2.2098 -0.9398)
			(stroke
				(width 0.1524)
				(type default)
			)
			(layer "B.SilkS")
		)
		(fp_line
			(start 2.2098 -0.9398)
			(end -2.2098 -0.9398)
			(stroke
				(width 0.1524)
				(type default)
			)
			(layer "B.SilkS")
		)
		(fp_line
			(start -2.2098 0.9398)
			(end 2.2098 0.9398)
			(stroke
				(width 0.1524)
				(type default)
			)
			(layer "B.SilkS")
		)
		(fp_line
			(start -2.2098 -0.9398)
			(end -2.2098 0.9398)
			(stroke
				(width 0.1524)
				(type default)
			)
			(layer "B.SilkS")
		)
		(fp_line
			(start 1.700022 0.899922)
			(end 1.700022 -0.899922)
			(stroke
				(width 0.1)
				(type default)
			)
			(layer "B.Fab")
		)
		(fp_line
			(start 1.700022 -0.899922)
			(end -1.700022 -0.899922)
			(stroke
				(width 0.1)
				(type default)
			)
			(layer "B.Fab")
		)
		(fp_line
			(start -1.700022 0.899922)
			(end 1.700022 0.899922)
			(stroke
				(width 0.1)
				(type default)
			)
			(layer "B.Fab")
		)
		(fp_line
			(start -1.700022 -0.899922)
			(end -1.700022 0.899922)
			(stroke
				(width 0.1)
				(type default)
			)
			(layer "B.Fab")
		)
		(pad "1" smd rect
			(at 1.4732 0 180)
			(size 1.1684 1.5748)
			(layers "B.Cu" "B.Mask" "B.Paste")
			(net "P52V_FAN_7")
		)
		(pad "2" smd rect
			(at -1.4732 0 180)
			(size 1.1684 1.5748)
			(layers "B.Cu" "B.Mask" "B.Paste")
			(net "GND")
		)
	)
	(footprint ""
		(layer "B.Cu")
		(at 10.795 -249.428 -90)
		(property "Reference" "PC2124"
			(at 0 0 90)
			(layer "B.SilkS")
			(hide yes)
			(effects
				(font
					(size 1.27 1.27)
				)
				(justify mirror)
			)
		)
		(property "Value" ""
			(at 0 0 90)
			(layer "B.Fab")
			(effects
				(font
					(size 1.27 1.27)
				)
				(justify mirror)
			)
		)
		(duplicate_pad_numbers_are_jumpers no)
		(fp_line
			(start -0.7874 0.4064)
			(end 0.7874 0.4064)
			(stroke
				(width 0.1524)
				(type default)
			)
			(layer "B.SilkS")
		)
		(fp_line
			(start 0.7874 0.4064)
			(end 0.7874 -0.4064)
			(stroke
				(width 0.1524)
				(type default)
			)
			(layer "B.SilkS")
		)
		(fp_line
			(start -0.7874 -0.4064)
			(end -0.7874 0.4064)
			(stroke
				(width 0.1524)
				(type default)
			)
			(layer "B.SilkS")
		)
		(fp_line
			(start 0.7874 -0.4064)
			(end -0.7874 -0.4064)
			(stroke
				(width 0.1524)
				(type default)
			)
			(layer "B.SilkS")
		)
		(fp_line
			(start -0.67945 0.3048)
			(end -0.120396 0.3048)
			(stroke
				(width 0.1)
				(type default)
			)
			(layer "B.Fab")
		)
		(fp_line
			(start -0.120396 0.3048)
			(end -0.120396 0.2794)
			(stroke
				(width 0.1)
				(type default)
			)
			(layer "B.Fab")
		)
		(fp_line
			(start 0.12065 0.3048)
			(end 0.67945 0.3048)
			(stroke
				(width 0.1)
				(type default)
			)
			(layer "B.Fab")
		)
		(fp_line
			(start 0.67945 0.3048)
			(end 0.67945 -0.305054)
			(stroke
				(width 0.1)
				(type default)
			)
			(layer "B.Fab")
		)
		(fp_line
			(start -0.120396 0.2794)
			(end 0.12065 0.2794)
			(stroke
				(width 0.1)
				(type default)
			)
			(layer "B.Fab")
		)
		(fp_line
			(start 0.12065 0.2794)
			(end 0.12065 0.3048)
			(stroke
				(width 0.1)
				(type default)
			)
			(layer "B.Fab")
		)
		(fp_line
			(start -0.12065 -0.2794)
			(end -0.12065 -0.3048)
			(stroke
				(width 0.1)
				(type default)
			)
			(layer "B.Fab")
		)
		(fp_line
			(start 0.12065 -0.2794)
			(end -0.12065 -0.2794)
			(stroke
				(width 0.1)
				(type default)
			)
			(layer "B.Fab")
		)
		(fp_line
			(start -0.67945 -0.3048)
			(end -0.67945 0.3048)
			(stroke
				(width 0.1)
				(type default)
			)
			(layer "B.Fab")
		)
		(fp_line
			(start -0.12065 -0.3048)
			(end -0.67945 -0.3048)
			(stroke
				(width 0.1)
				(type default)
			)
			(layer "B.Fab")
		)
		(fp_line
			(start 0.12065 -0.305054)
			(end 0.12065 -0.2794)
			(stroke
				(width 0.1)
				(type default)
			)
			(layer "B.Fab")
		)
		(fp_line
			(start 0.67945 -0.305054)
			(end 0.12065 -0.305054)
			(stroke
				(width 0.1)
				(type default)
			)
			(layer "B.Fab")
		)
		(pad "1" smd circle
			(at 0.40005 0 90)
			(size 0 0)
			(layers "B.Cu" "B.Mask" "B.Paste")
			(net "FAN_6_TEMP")
		)
		(pad "2" smd circle
			(at -0.40005 0 90)
			(size 0 0)
			(layers "B.Cu" "B.Mask" "B.Paste")
			(net "GND")
		)
	)
	(footprint ""
		(layer "B.Cu")
		(at 6.223 -64.389 180)
		(property "Reference" "PR53"
			(at 0 0 0)
			(layer "B.SilkS")
			(hide yes)
			(effects
				(font
					(size 1.27 1.27)
				)
				(justify mirror)
			)
		)
		(property "Value" ""
			(at 0 0 0)
			(layer "B.Fab")
			(effects
				(font
					(size 1.27 1.27)
				)
				(justify mirror)
			)
		)
		(duplicate_pad_numbers_are_jumpers no)
		(fp_line
			(start 0.7874 0.4064)
			(end 0.7874 -0.4064)
			(stroke
				(width 0.1524)
				(type default)
			)
			(layer "B.SilkS")
		)
		(fp_line
			(start 0.7874 -0.4064)
			(end -0.7874 -0.4064)
			(stroke
				(width 0.1524)
				(type default)
			)
			(layer "B.SilkS")
		)
		(fp_line
			(start -0.7874 0.4064)
			(end 0.7874 0.4064)
			(stroke
				(width 0.1524)
				(type default)
			)
			(layer "B.SilkS")
		)
		(fp_line
			(start -0.7874 -0.4064)
			(end -0.7874 0.4064)
			(stroke
				(width 0.1524)
				(type default)
			)
			(layer "B.SilkS")
		)
		(fp_line
			(start 0.67945 0.3048)
			(end 0.67945 -0.305054)
			(stroke
				(width 0.1)
				(type default)
			)
			(layer "B.Fab")
		)
		(fp_line
			(start 0.67945 -0.305054)
			(end 0.12065 -0.305054)
			(stroke
				(width 0.1)
				(type default)
			)
			(layer "B.Fab")
		)
		(fp_line
			(start 0.12065 0.3048)
			(end 0.67945 0.3048)
			(stroke
				(width 0.1)
				(type default)
			)
			(layer "B.Fab")
		)
		(fp_line
			(start 0.12065 0.2794)
			(end 0.12065 0.3048)
			(stroke
				(width 0.1)
				(type default)
			)
			(layer "B.Fab")
		)
		(fp_line
			(start 0.12065 -0.2794)
			(end -0.12065 -0.2794)
			(stroke
				(width 0.1)
				(type default)
			)
			(layer "B.Fab")
		)
		(fp_line
			(start 0.12065 -0.305054)
			(end 0.12065 -0.2794)
			(stroke
				(width 0.1)
				(type default)
			)
			(layer "B.Fab")
		)
		(fp_line
			(start -0.120396 0.3048)
			(end -0.120396 0.2794)
			(stroke
				(width 0.1)
				(type default)
			)
			(layer "B.Fab")
		)
		(fp_line
			(start -0.120396 0.2794)
			(end 0.12065 0.2794)
			(stroke
				(width 0.1)
				(type default)
			)
			(layer "B.Fab")
		)
		(fp_line
			(start -0.12065 -0.2794)
			(end -0.12065 -0.3048)
			(stroke
				(width 0.1)
				(type default)
			)
			(layer "B.Fab")
		)
		(fp_line
			(start -0.12065 -0.3048)
			(end -0.67945 -0.3048)
			(stroke
				(width 0.1)
				(type default)
			)
			(layer "B.Fab")
		)
		(fp_line
			(start -0.67945 0.3048)
			(end -0.120396 0.3048)
			(stroke
				(width 0.1)
				(type default)
			)
			(layer "B.Fab")
		)
		(fp_line
			(start -0.67945 -0.3048)
			(end -0.67945 0.3048)
			(stroke
				(width 0.1)
				(type default)
			)
			(layer "B.Fab")
		)
		(pad "1" smd circle
			(at 0.40005 0)
			(size 0 0)
			(layers "B.Cu" "B.Mask" "B.Paste")
			(net "FAN_4_CLREF")
		)
		(pad "2" smd circle
			(at -0.40005 0)
			(size 0 0)
			(layers "B.Cu" "B.Mask" "B.Paste")
			(net "GND")
		)
	)
	(footprint ""
		(layer "B.Cu")
		(at 40.894 -134.62 180)
		(property "Reference" "R5426"
			(at 0 0 0)
			(layer "B.SilkS")
			(hide yes)
			(effects
				(font
					(size 1.27 1.27)
				)
				(justify mirror)
			)
		)
		(property "Value" ""
			(at 0 0 0)
			(layer "B.Fab")
			(effects
				(font
					(size 1.27 1.27)
				)
				(justify mirror)
			)
		)
		(duplicate_pad_numbers_are_jumpers no)
		(fp_line
			(start 0.7874 0.4064)
			(end 0.7874 -0.4064)
			(stroke
				(width 0.1524)
				(type default)
			)
			(layer "B.SilkS")
		)
		(fp_line
			(start 0.7874 -0.4064)
			(end -0.7874 -0.4064)
			(stroke
				(width 0.1524)
				(type default)
			)
			(layer "B.SilkS")
		)
		(fp_line
			(start -0.7874 0.4064)
			(end 0.7874 0.4064)
			(stroke
				(width 0.1524)
				(type default)
			)
			(layer "B.SilkS")
		)
		(fp_line
			(start -0.7874 -0.4064)
			(end -0.7874 0.4064)
			(stroke
				(width 0.1524)
				(type default)
			)
			(layer "B.SilkS")
		)
		(fp_line
			(start 0.67945 0.3048)
			(end 0.67945 -0.305054)
			(stroke
				(width 0.1)
				(type default)
			)
			(layer "B.Fab")
		)
		(fp_line
			(start 0.67945 -0.305054)
			(end 0.12065 -0.305054)
			(stroke
				(width 0.1)
				(type default)
			)
			(layer "B.Fab")
		)
		(fp_line
			(start 0.12065 0.3048)
			(end 0.67945 0.3048)
			(stroke
				(width 0.1)
				(type default)
			)
			(layer "B.Fab")
		)
		(fp_line
			(start 0.12065 0.2794)
			(end 0.12065 0.3048)
			(stroke
				(width 0.1)
				(type default)
			)
			(layer "B.Fab")
		)
		(fp_line
			(start 0.12065 -0.2794)
			(end -0.12065 -0.2794)
			(stroke
				(width 0.1)
				(type default)
			)
			(layer "B.Fab")
		)
		(fp_line
			(start 0.12065 -0.305054)
			(end 0.12065 -0.2794)
			(stroke
				(width 0.1)
				(type default)
			)
			(layer "B.Fab")
		)
		(fp_line
			(start -0.120396 0.3048)
			(end -0.120396 0.2794)
			(stroke
				(width 0.1)
				(type default)
			)
			(layer "B.Fab")
		)
		(fp_line
			(start -0.120396 0.2794)
			(end 0.12065 0.2794)
			(stroke
				(width 0.1)
				(type default)
			)
			(layer "B.Fab")
		)
		(fp_line
			(start -0.12065 -0.2794)
			(end -0.12065 -0.3048)
			(stroke
				(width 0.1)
				(type default)
			)
			(layer "B.Fab")
		)
		(fp_line
			(start -0.12065 -0.3048)
			(end -0.67945 -0.3048)
			(stroke
				(width 0.1)
				(type default)
			)
			(layer "B.Fab")
		)
		(fp_line
			(start -0.67945 0.3048)
			(end -0.120396 0.3048)
			(stroke
				(width 0.1)
				(type default)
			)
			(layer "B.Fab")
		)
		(fp_line
			(start -0.67945 -0.3048)
			(end -0.67945 0.3048)
			(stroke
				(width 0.1)
				(type default)
			)
			(layer "B.Fab")
		)
		(pad "1" smd rect
			(at 0.40005 0 180)
			(size 0.4572 0.508)
			(layers "B.Cu" "B.Mask" "B.Paste")
			(net "FAN_0_TACH_IL")
		)
		(pad "2" smd rect
			(at -0.40005 0 180)
			(size 0.4572 0.508)
			(layers "B.Cu" "B.Mask" "B.Paste")
			(net "GND")
		)
	)
	(footprint ""
		(layer "B.Cu")
		(at 44.6786 -54.8386 180)
		(property "Reference" "PC36"
			(at 0 0 0)
			(layer "B.SilkS")
			(hide yes)
			(effects
				(font
					(size 1.27 1.27)
				)
				(justify mirror)
			)
		)
		(property "Value" ""
			(at 0 0 0)
			(layer "B.Fab")
			(effects
				(font
					(size 1.27 1.27)
				)
				(justify mirror)
			)
		)
		(duplicate_pad_numbers_are_jumpers no)
		(fp_line
			(start 1.524 0.762)
			(end 1.524 -0.762)
			(stroke
				(width 0.1524)
				(type default)
			)
			(layer "B.SilkS")
		)
		(fp_line
			(start 1.524 -0.762)
			(end -1.524 -0.762)
			(stroke
				(width 0.1524)
				(type default)
			)
			(layer "B.SilkS")
		)
		(fp_line
			(start -1.524 0.762)
			(end 1.524 0.762)
			(stroke
				(width 0.1524)
				(type default)
			)
			(layer "B.SilkS")
		)
		(fp_line
			(start -1.524 -0.762)
			(end -1.524 0.762)
			(stroke
				(width 0.1524)
				(type default)
			)
			(layer "B.SilkS")
		)
		(fp_line
			(start 1.1049 0.724916)
			(end -1.1049 0.724916)
			(stroke
				(width 0.1)
				(type default)
			)
			(layer "B.Fab")
		)
		(fp_line
			(start 1.1049 -0.724916)
			(end 1.1049 0.724916)
			(stroke
				(width 0.1)
				(type default)
			)
			(layer "B.Fab")
		)
		(fp_line
			(start -1.1049 0.724916)
			(end -1.1049 -0.724916)
			(stroke
				(width 0.1)
				(type default)
			)
			(layer "B.Fab")
		)
		(fp_line
			(start -1.1049 -0.724916)
			(end 1.1049 -0.724916)
			(stroke
				(width 0.1)
				(type default)
			)
			(layer "B.Fab")
		)
		(pad "1" smd rect
			(at 0.889 0 180)
			(size 1.016 1.27)
			(layers "B.Cu" "B.Mask" "B.Paste")
			(net "P52V_FAN_3")
		)
		(pad "2" smd rect
			(at -0.889 0 180)
			(size 1.016 1.27)
			(layers "B.Cu" "B.Mask" "B.Paste")
			(net "GND")
		)
	)
)
